(kicad_pcb
	(version 20260206)
	(generator "pcbnew")
	(generator_version "10.0")
	(general
		(thickness 1.6)
		(legacy_teardrops no)
	)
	(paper "A4")
	(title_block
		(title "03242023_DA0F0TMBIJ0_F0T_Motherboard_J_brd_V01_OCP.brd")
		(comment 1 "Grand Teton / footprints 92-98 of 6105")
	)
	(layers
		(0 "F.Cu" signal "TOP")
		(4 "In1.Cu" signal "GND")
		(6 "In2.Cu" signal "IN1")
		(8 "In3.Cu" signal "GND1")
		(10 "In4.Cu" signal "IN2")
		(12 "In5.Cu" signal "GND2")
		(14 "In6.Cu" signal "IN3")
		(16 "In7.Cu" signal "GND3")
		(18 "In8.Cu" signal "VCC")
		(20 "In9.Cu" signal "VCC1")
		(22 "In10.Cu" signal "GND4")
		(24 "In11.Cu" signal "IN4")
		(26 "In12.Cu" signal "GND5")
		(28 "In13.Cu" signal "IN5")
		(30 "In14.Cu" signal "GND6")
		(32 "In15.Cu" signal "IN6")
		(34 "In16.Cu" signal "GND7")
		(2 "B.Cu" signal "BOTTOM")
		(9 "F.Adhes" user "F.Adhesive")
		(11 "B.Adhes" user "B.Adhesive")
		(13 "F.Paste" user "Package Geometry/Pastemask Top")
		(15 "B.Paste" user "Package Geometry/Pastemask Bottom")
		(5 "F.SilkS" user "Ref Des/Silkscreen Top")
		(7 "B.SilkS" user "Ref Des/Silkscreen Bottom")
		(1 "F.Mask" user "Board Geometry/Soldermask Top")
		(3 "B.Mask" user "Board Geometry/Soldermask Bottom")
		(17 "Dwgs.User" user "User.Drawings")
		(19 "Cmts.User" user "User.Comments")
		(21 "Eco1.User" user "User.Eco1")
		(23 "Eco2.User" user "User.Eco2")
		(25 "Edge.Cuts" user "Board Geometry/Outline")
		(27 "Margin" user)
		(31 "F.CrtYd" user "Package Geometry/Place Bound Top")
		(29 "B.CrtYd" user "Package Geometry/Place Bound Bottom")
		(35 "F.Fab" user "Ref Des/Assembly Top")
		(33 "B.Fab" user "Ref Des/Assembly Bottom")
	)
	(footprint ""
		(layer "F.Cu")
		(at 114.706654 -357.91775)
		(property "Reference" "PC554"
			(at 0 0 0)
			(layer "F.SilkS")
			(hide yes)
			(effects
				(font
					(size 1.27 1.27)
				)
			)
		)
		(property "Value" ""
			(at 0 0 0)
			(layer "F.Fab")
			(effects
				(font
					(size 1.27 1.27)
				)
			)
		)
		(duplicate_pad_numbers_are_jumpers no)
		(fp_line
			(start -0.7874 -0.4064)
			(end 0.7874 -0.4064)
			(stroke
				(width 0.1524)
				(type default)
			)
			(layer "F.SilkS")
		)
		(fp_line
			(start -0.7874 0.4064)
			(end -0.7874 -0.4064)
			(stroke
				(width 0.1524)
				(type default)
			)
			(layer "F.SilkS")
		)
		(fp_line
			(start 0.7874 -0.4064)
			(end 0.7874 0.4064)
			(stroke
				(width 0.1524)
				(type default)
			)
			(layer "F.SilkS")
		)
		(fp_line
			(start 0.7874 0.4064)
			(end -0.7874 0.4064)
			(stroke
				(width 0.1524)
				(type default)
			)
			(layer "F.SilkS")
		)
		(fp_line
			(start -0.67945 -0.305054)
			(end -0.12065 -0.305054)
			(stroke
				(width 0.1)
				(type default)
			)
			(layer "F.Fab")
		)
		(fp_line
			(start -0.67945 0.3048)
			(end -0.67945 -0.305054)
			(stroke
				(width 0.1)
				(type default)
			)
			(layer "F.Fab")
		)
		(fp_line
			(start -0.12065 -0.305054)
			(end -0.12065 -0.2794)
			(stroke
				(width 0.1)
				(type default)
			)
			(layer "F.Fab")
		)
		(fp_line
			(start -0.12065 -0.2794)
			(end 0.12065 -0.2794)
			(stroke
				(width 0.1)
				(type default)
			)
			(layer "F.Fab")
		)
		(fp_line
			(start -0.12065 0.2794)
			(end -0.12065 0.3048)
			(stroke
				(width 0.1)
				(type default)
			)
			(layer "F.Fab")
		)
		(fp_line
			(start -0.12065 0.3048)
			(end -0.67945 0.3048)
			(stroke
				(width 0.1)
				(type default)
			)
			(layer "F.Fab")
		)
		(fp_line
			(start 0.120396 0.2794)
			(end -0.12065 0.2794)
			(stroke
				(width 0.1)
				(type default)
			)
			(layer "F.Fab")
		)
		(fp_line
			(start 0.120396 0.3048)
			(end 0.120396 0.2794)
			(stroke
				(width 0.1)
				(type default)
			)
			(layer "F.Fab")
		)
		(fp_line
			(start 0.12065 -0.3048)
			(end 0.67945 -0.3048)
			(stroke
				(width 0.1)
				(type default)
			)
			(layer "F.Fab")
		)
		(fp_line
			(start 0.12065 -0.2794)
			(end 0.12065 -0.3048)
			(stroke
				(width 0.1)
				(type default)
			)
			(layer "F.Fab")
		)
		(fp_line
			(start 0.67945 -0.3048)
			(end 0.67945 0.3048)
			(stroke
				(width 0.1)
				(type default)
			)
			(layer "F.Fab")
		)
		(fp_line
			(start 0.67945 0.3048)
			(end 0.120396 0.3048)
			(stroke
				(width 0.1)
				(type default)
			)
			(layer "F.Fab")
		)
		(pad "1" smd circle
			(at -0.40005 0)
			(size 0 0)
			(layers "F.Cu" "F.Mask" "F.Paste")
			(net "PVCCIN_CPU1_ATSEN")
		)
		(pad "2" smd circle
			(at 0.40005 0)
			(size 0 0)
			(layers "F.Cu" "F.Mask" "F.Paste")
			(net "GND")
		)
	)
	(footprint ""
		(layer "F.Cu")
		(at 243.03228 -121.986548)
		(property "Reference" "R3200"
			(at 0 0 0)
			(layer "F.SilkS")
			(hide yes)
			(effects
				(font
					(size 1.27 1.27)
				)
			)
		)
		(property "Value" ""
			(at 0 0 0)
			(layer "F.Fab")
			(effects
				(font
					(size 1.27 1.27)
				)
			)
		)
		(duplicate_pad_numbers_are_jumpers no)
		(fp_line
			(start -0.7874 0.4064)
			(end -0.7874 -0.057912)
			(stroke
				(width 0.1524)
				(type default)
			)
			(layer "F.SilkS")
		)
		(fp_line
			(start -0.45212 -0.4064)
			(end 0.47498 -0.4064)
			(stroke
				(width 0.1524)
				(type default)
			)
			(layer "F.SilkS")
		)
		(fp_line
			(start 0.7874 -0.113792)
			(end 0.7874 0.4064)
			(stroke
				(width 0.1524)
				(type default)
			)
			(layer "F.SilkS")
		)
		(fp_line
			(start 0.7874 0.4064)
			(end -0.7874 0.4064)
			(stroke
				(width 0.1524)
				(type default)
			)
			(layer "F.SilkS")
		)
		(fp_line
			(start -0.67945 -0.305054)
			(end -0.12065 -0.305054)
			(stroke
				(width 0.1)
				(type default)
			)
			(layer "F.Fab")
		)
		(fp_line
			(start -0.67945 0.3048)
			(end -0.67945 -0.305054)
			(stroke
				(width 0.1)
				(type default)
			)
			(layer "F.Fab")
		)
		(fp_line
			(start -0.12065 -0.305054)
			(end -0.12065 -0.2794)
			(stroke
				(width 0.1)
				(type default)
			)
			(layer "F.Fab")
		)
		(fp_line
			(start -0.12065 -0.2794)
			(end 0.12065 -0.2794)
			(stroke
				(width 0.1)
				(type default)
			)
			(layer "F.Fab")
		)
		(fp_line
			(start -0.12065 0.2794)
			(end -0.12065 0.3048)
			(stroke
				(width 0.1)
				(type default)
			)
			(layer "F.Fab")
		)
		(fp_line
			(start -0.12065 0.3048)
			(end -0.67945 0.3048)
			(stroke
				(width 0.1)
				(type default)
			)
			(layer "F.Fab")
		)
		(fp_line
			(start 0.120396 0.2794)
			(end -0.12065 0.2794)
			(stroke
				(width 0.1)
				(type default)
			)
			(layer "F.Fab")
		)
		(fp_line
			(start 0.120396 0.3048)
			(end 0.120396 0.2794)
			(stroke
				(width 0.1)
				(type default)
			)
			(layer "F.Fab")
		)
		(fp_line
			(start 0.12065 -0.3048)
			(end 0.67945 -0.3048)
			(stroke
				(width 0.1)
				(type default)
			)
			(layer "F.Fab")
		)
		(fp_line
			(start 0.12065 -0.2794)
			(end 0.12065 -0.3048)
			(stroke
				(width 0.1)
				(type default)
			)
			(layer "F.Fab")
		)
		(fp_line
			(start 0.67945 -0.3048)
			(end 0.67945 0.3048)
			(stroke
				(width 0.1)
				(type default)
			)
			(layer "F.Fab")
		)
		(fp_line
			(start 0.67945 0.3048)
			(end 0.120396 0.3048)
			(stroke
				(width 0.1)
				(type default)
			)
			(layer "F.Fab")
		)
		(pad "1" smd circle
			(at -0.40005 0)
			(size 0 0)
			(layers "F.Cu" "F.Mask" "F.Paste")
			(net "CLK_100M_OCP_V3_2_D_R_DP")
		)
		(pad "2" smd circle
			(at 0.40005 0)
			(size 0 0)
			(layers "F.Cu" "F.Mask" "F.Paste")
			(net "CLK_100M_OCP_V3_2_D_DP")
		)
	)
	(footprint ""
		(layer "F.Cu")
		(at 236.649768 -272.499836)
		(property "Reference" "H99"
			(at -4.60756 -4.956048 0)
			(unlocked yes)
			(layer "F.SilkS")
			(effects
				(font
					(size 0.7874 0.5842)
					(thickness 0.1524)
				)
				(justify left)
			)
		)
		(property "Value" ""
			(at 0 0 0)
			(layer "F.Fab")
			(effects
				(font
					(size 1.27 1.27)
				)
			)
		)
		(duplicate_pad_numbers_are_jumpers no)
		(pad "1" thru_hole circle
			(at 0 0)
			(size 10.0076 10.0076)
			(drill 5.6134)
			(layers "*.Cu" "*.Mask")
			(remove_unused_layers no)
			(net "GND")
			(clearance -1.9431)
		)
	)
	(footprint ""
		(layer "F.Cu")
		(at 106.86542 -418.392864 180)
		(property "Reference" "R4477"
			(at 0 0 180)
			(layer "F.SilkS")
			(hide yes)
			(effects
				(font
					(size 1.27 1.27)
				)
			)
		)
		(property "Value" ""
			(at 0 0 180)
			(layer "F.Fab")
			(effects
				(font
					(size 1.27 1.27)
				)
			)
		)
		(duplicate_pad_numbers_are_jumpers no)
		(fp_line
			(start 0.7874 0.4064)
			(end -0.7874 0.4064)
			(stroke
				(width 0.1524)
				(type default)
			)
			(layer "F.SilkS")
		)
		(fp_line
			(start 0.7874 -0.4064)
			(end 0.7874 0.4064)
			(stroke
				(width 0.1524)
				(type default)
			)
			(layer "F.SilkS")
		)
		(fp_line
			(start -0.7874 0.4064)
			(end -0.7874 -0.4064)
			(stroke
				(width 0.1524)
				(type default)
			)
			(layer "F.SilkS")
		)
		(fp_line
			(start -0.7874 -0.4064)
			(end 0.7874 -0.4064)
			(stroke
				(width 0.1524)
				(type default)
			)
			(layer "F.SilkS")
		)
		(fp_line
			(start 0.67945 0.3048)
			(end 0.120396 0.3048)
			(stroke
				(width 0.1)
				(type default)
			)
			(layer "F.Fab")
		)
		(fp_line
			(start 0.67945 -0.3048)
			(end 0.67945 0.3048)
			(stroke
				(width 0.1)
				(type default)
			)
			(layer "F.Fab")
		)
		(fp_line
			(start 0.12065 -0.2794)
			(end 0.12065 -0.3048)
			(stroke
				(width 0.1)
				(type default)
			)
			(layer "F.Fab")
		)
		(fp_line
			(start 0.12065 -0.3048)
			(end 0.67945 -0.3048)
			(stroke
				(width 0.1)
				(type default)
			)
			(layer "F.Fab")
		)
		(fp_line
			(start 0.120396 0.3048)
			(end 0.120396 0.2794)
			(stroke
				(width 0.1)
				(type default)
			)
			(layer "F.Fab")
		)
		(fp_line
			(start 0.120396 0.2794)
			(end -0.12065 0.2794)
			(stroke
				(width 0.1)
				(type default)
			)
			(layer "F.Fab")
		)
		(fp_line
			(start -0.12065 0.3048)
			(end -0.67945 0.3048)
			(stroke
				(width 0.1)
				(type default)
			)
			(layer "F.Fab")
		)
		(fp_line
			(start -0.12065 0.2794)
			(end -0.12065 0.3048)
			(stroke
				(width 0.1)
				(type default)
			)
			(layer "F.Fab")
		)
		(fp_line
			(start -0.12065 -0.2794)
			(end 0.12065 -0.2794)
			(stroke
				(width 0.1)
				(type default)
			)
			(layer "F.Fab")
		)
		(fp_line
			(start -0.12065 -0.305054)
			(end -0.12065 -0.2794)
			(stroke
				(width 0.1)
				(type default)
			)
			(layer "F.Fab")
		)
		(fp_line
			(start -0.67945 0.3048)
			(end -0.67945 -0.305054)
			(stroke
				(width 0.1)
				(type default)
			)
			(layer "F.Fab")
		)
		(fp_line
			(start -0.67945 -0.305054)
			(end -0.12065 -0.305054)
			(stroke
				(width 0.1)
				(type default)
			)
			(layer "F.Fab")
		)
		(pad "1" smd circle
			(at -0.40005 0 180)
			(size 0 0)
			(layers "F.Cu" "F.Mask" "F.Paste")
			(net "FM_9ZXL045_0_OE_N")
		)
		(pad "2" smd circle
			(at 0.40005 0 180)
			(size 0 0)
			(layers "F.Cu" "F.Mask" "F.Paste")
			(net "CLK_SWB_BUF2_OE_N")
		)
	)
	(footprint ""
		(layer "F.Cu")
		(at 357.548942 -389.19277 180)
		(property "Reference" "C2273"
			(at 0 0 180)
			(layer "F.SilkS")
			(hide yes)
			(effects
				(font
					(size 1.27 1.27)
				)
			)
		)
		(property "Value" ""
			(at 0 0 180)
			(layer "F.Fab")
			(effects
				(font
					(size 1.27 1.27)
				)
			)
		)
		(duplicate_pad_numbers_are_jumpers no)
		(fp_line
			(start 0.7874 0.4064)
			(end -0.7874 0.4064)
			(stroke
				(width 0.1524)
				(type default)
			)
			(layer "F.SilkS")
		)
		(fp_line
			(start 0.7874 -0.4064)
			(end 0.7874 0.4064)
			(stroke
				(width 0.1524)
				(type default)
			)
			(layer "F.SilkS")
		)
		(fp_line
			(start -0.7874 0.4064)
			(end -0.7874 -0.4064)
			(stroke
				(width 0.1524)
				(type default)
			)
			(layer "F.SilkS")
		)
		(fp_line
			(start -0.7874 -0.4064)
			(end 0.7874 -0.4064)
			(stroke
				(width 0.1524)
				(type default)
			)
			(layer "F.SilkS")
		)
		(fp_line
			(start 0.67945 0.3048)
			(end 0.120396 0.3048)
			(stroke
				(width 0.1)
				(type default)
			)
			(layer "F.Fab")
		)
		(fp_line
			(start 0.67945 -0.3048)
			(end 0.67945 0.3048)
			(stroke
				(width 0.1)
				(type default)
			)
			(layer "F.Fab")
		)
		(fp_line
			(start 0.12065 -0.2794)
			(end 0.12065 -0.3048)
			(stroke
				(width 0.1)
				(type default)
			)
			(layer "F.Fab")
		)
		(fp_line
			(start 0.12065 -0.3048)
			(end 0.67945 -0.3048)
			(stroke
				(width 0.1)
				(type default)
			)
			(layer "F.Fab")
		)
		(fp_line
			(start 0.120396 0.3048)
			(end 0.120396 0.2794)
			(stroke
				(width 0.1)
				(type default)
			)
			(layer "F.Fab")
		)
		(fp_line
			(start 0.120396 0.2794)
			(end -0.12065 0.2794)
			(stroke
				(width 0.1)
				(type default)
			)
			(layer "F.Fab")
		)
		(fp_line
			(start -0.12065 0.3048)
			(end -0.67945 0.3048)
			(stroke
				(width 0.1)
				(type default)
			)
			(layer "F.Fab")
		)
		(fp_line
			(start -0.12065 0.2794)
			(end -0.12065 0.3048)
			(stroke
				(width 0.1)
				(type default)
			)
			(layer "F.Fab")
		)
		(fp_line
			(start -0.12065 -0.2794)
			(end 0.12065 -0.2794)
			(stroke
				(width 0.1)
				(type default)
			)
			(layer "F.Fab")
		)
		(fp_line
			(start -0.12065 -0.305054)
			(end -0.12065 -0.2794)
			(stroke
				(width 0.1)
				(type default)
			)
			(layer "F.Fab")
		)
		(fp_line
			(start -0.67945 0.3048)
			(end -0.67945 -0.305054)
			(stroke
				(width 0.1)
				(type default)
			)
			(layer "F.Fab")
		)
		(fp_line
			(start -0.67945 -0.305054)
			(end -0.12065 -0.305054)
			(stroke
				(width 0.1)
				(type default)
			)
			(layer "F.Fab")
		)
		(pad "1" smd circle
			(at -0.40005 0 180)
			(size 0 0)
			(layers "F.Cu" "F.Mask" "F.Paste")
			(net "GPU_3V3IO_RSVD3_ISO")
		)
		(pad "2" smd circle
			(at 0.40005 0 180)
			(size 0 0)
			(layers "F.Cu" "F.Mask" "F.Paste")
			(net "GND")
		)
	)
	(footprint ""
		(layer "F.Cu")
		(at 459.437486 -93.627448)
		(property "Reference" "U224"
			(at -1.651 -1.793748 0)
			(unlocked yes)
			(layer "F.SilkS")
			(effects
				(font
					(size 0.7874 0.5842)
					(thickness 0.1524)
				)
				(justify left)
			)
		)
		(property "Value" ""
			(at 0 0 0)
			(layer "F.Fab")
			(effects
				(font
					(size 1.27 1.27)
				)
			)
		)
		(duplicate_pad_numbers_are_jumpers no)
		(fp_line
			(start -1.400048 1.100074)
			(end -1.400048 -1.100074)
			(stroke
				(width 0.1524)
				(type default)
			)
			(layer "F.SilkS")
		)
		(fp_line
			(start 1.400048 -1.100074)
			(end -1.400048 -1.100074)
			(stroke
				(width 0.1524)
				(type default)
			)
			(layer "F.SilkS")
		)
		(fp_line
			(start 1.400048 -1.100074)
			(end 1.400048 1.100074)
			(stroke
				(width 0.1524)
				(type default)
			)
			(layer "F.SilkS")
		)
		(fp_line
			(start 1.400048 1.100074)
			(end -1.400048 1.100074)
			(stroke
				(width 0.1524)
				(type default)
			)
			(layer "F.SilkS")
		)
		(fp_poly
			(pts
				(xy -1.590548 -0.649986) (xy -2.606548 -0.141986) (xy -2.606548 -1.157986)
			)
			(stroke
				(width 0)
				(type default)
			)
			(fill yes)
			(layer "F.SilkS")
		)
		(fp_line
			(start -0.674878 -1.100074)
			(end 0.674878 -1.100074)
			(stroke
				(width 0.1)
				(type default)
			)
			(layer "F.Fab")
		)
		(fp_line
			(start -0.674878 1.100074)
			(end -0.674878 -1.100074)
			(stroke
				(width 0.1)
				(type default)
			)
			(layer "F.Fab")
		)
		(fp_line
			(start 0.674878 -1.100074)
			(end 0.674878 1.100074)
			(stroke
				(width 0.1)
				(type default)
			)
			(layer "F.Fab")
		)
		(fp_line
			(start 0.674878 1.100074)
			(end -0.674878 1.100074)
			(stroke
				(width 0.1)
				(type default)
			)
			(layer "F.Fab")
		)
		(fp_poly
			(pts
				(xy -1.590548 -0.649986) (xy -2.606548 -1.157986) (xy -2.606548 -0.141986)
			)
			(stroke
				(width 0)
				(type default)
			)
			(fill yes)
			(layer "F.Fab")
		)
		(pad "1" smd rect
			(at -0.94996 -0.649986 270)
			(size 0.4318 0.6096)
			(layers "F.Cu" "F.Mask" "F.Paste")
			(net "OCP_SFF_AUX_PWR_EN_R4")
		)
		(pad "2" smd rect
			(at -0.94996 0 270)
			(size 0.4318 0.6096)
			(layers "F.Cu" "F.Mask" "F.Paste")
			(net "RST_SMB_SWITCH_N")
		)
		(pad "3" smd rect
			(at -0.94996 0.649986 270)
			(size 0.4318 0.6096)
			(layers "F.Cu" "F.Mask" "F.Paste")
			(net "GND")
		)
		(pad "4" smd rect
			(at 0.94996 0.649986 270)
			(size 0.4318 0.6096)
			(layers "F.Cu" "F.Mask" "F.Paste")
			(net "RST_HP_OCP_SFF_R_N")
		)
		(pad "5" smd rect
			(at 0.94996 -0.649986 270)
			(size 0.4318 0.6096)
			(layers "F.Cu" "F.Mask" "F.Paste")
			(net "P3V3_AUX")
		)
	)
	(footprint ""
		(layer "F.Cu")
		(at 436.526432 -27.275536 90)
		(property "Reference" "PR3840"
			(at 0 0 90)
			(layer "F.SilkS")
			(hide yes)
			(effects
				(font
					(size 1.27 1.27)
				)
			)
		)
		(property "Value" ""
			(at 0 0 90)
			(layer "F.Fab")
			(effects
				(font
					(size 1.27 1.27)
				)
			)
		)
		(duplicate_pad_numbers_are_jumpers no)
		(fp_line
			(start 0.7874 -0.4064)
			(end 0.7874 0.4064)
			(stroke
				(width 0.1524)
				(type default)
			)
			(layer "F.SilkS")
		)
		(fp_line
			(start -0.7874 -0.4064)
			(end 0.7874 -0.4064)
			(stroke
				(width 0.1524)
				(type default)
			)
			(layer "F.SilkS")
		)
		(fp_line
			(start 0.7874 0.4064)
			(end -0.7874 0.4064)
			(stroke
				(width 0.1524)
				(type default)
			)
			(layer "F.SilkS")
		)
		(fp_line
			(start -0.7874 0.4064)
			(end -0.7874 -0.4064)
			(stroke
				(width 0.1524)
				(type default)
			)
			(layer "F.SilkS")
		)
		(fp_line
			(start -0.12065 -0.305054)
			(end -0.12065 -0.2794)
			(stroke
				(width 0.1)
				(type default)
			)
			(layer "F.Fab")
		)
		(fp_line
			(start -0.67945 -0.305054)
			(end -0.12065 -0.305054)
			(stroke
				(width 0.1)
				(type default)
			)
			(layer "F.Fab")
		)
		(fp_line
			(start 0.67945 -0.3048)
			(end 0.67945 0.3048)
			(stroke
				(width 0.1)
				(type default)
			)
			(layer "F.Fab")
		)
		(fp_line
			(start 0.12065 -0.3048)
			(end 0.67945 -0.3048)
			(stroke
				(width 0.1)
				(type default)
			)
			(layer "F.Fab")
		)
		(fp_line
			(start 0.12065 -0.2794)
			(end 0.12065 -0.3048)
			(stroke
				(width 0.1)
				(type default)
			)
			(layer "F.Fab")
		)
		(fp_line
			(start -0.12065 -0.2794)
			(end 0.12065 -0.2794)
			(stroke
				(width 0.1)
				(type default)
			)
			(layer "F.Fab")
		)
		(fp_line
			(start 0.120396 0.2794)
			(end -0.12065 0.2794)
			(stroke
				(width 0.1)
				(type default)
			)
			(layer "F.Fab")
		)
		(fp_line
			(start -0.12065 0.2794)
			(end -0.12065 0.3048)
			(stroke
				(width 0.1)
				(type default)
			)
			(layer "F.Fab")
		)
		(fp_line
			(start 0.67945 0.3048)
			(end 0.120396 0.3048)
			(stroke
				(width 0.1)
				(type default)
			)
			(layer "F.Fab")
		)
		(fp_line
			(start 0.120396 0.3048)
			(end 0.120396 0.2794)
			(stroke
				(width 0.1)
				(type default)
			)
			(layer "F.Fab")
		)
		(fp_line
			(start -0.12065 0.3048)
			(end -0.67945 0.3048)
			(stroke
				(width 0.1)
				(type default)
			)
			(layer "F.Fab")
		)
		(fp_line
			(start -0.67945 0.3048)
			(end -0.67945 -0.305054)
			(stroke
				(width 0.1)
				(type default)
			)
			(layer "F.Fab")
		)
		(pad "1" smd circle
			(at -0.40005 0 90)
			(size 0 0)
			(layers "F.Cu" "F.Mask" "F.Paste")
			(net "P12V_OCP_SFF")
		)
		(pad "2" smd circle
			(at 0.40005 0 90)
			(size 0 0)
			(layers "F.Cu" "F.Mask" "F.Paste")
			(net "P12V_OCP_OV_FB_1")
		)
	)
)
